(kicad_pcb
	(version 20241229)
	(generator "pcbnew")
	(generator_version "9.0")
	(general
		(thickness 1.294)
		(legacy_teardrops no)
	)
	(paper "A3")
	(title_block
		(title "Kintex 410T devboard")
		(date "2024-04-03")
		(rev "1.1.2")
		(comment 9 "footprints 320-324 of 975")
	)
	(layers
		(0 "F.Cu" mixed)
		(4 "In1.Cu" power)
		(6 "In2.Cu" power)
		(8 "In3.Cu" mixed)
		(10 "In4.Cu" power)
		(12 "In5.Cu" mixed)
		(14 "In6.Cu" power)
		(16 "In7.Cu" mixed)
		(18 "In8.Cu" power)
		(2 "B.Cu" mixed)
		(9 "F.Adhes" user "F.Adhesive")
		(11 "B.Adhes" user "B.Adhesive")
		(13 "F.Paste" user)
		(15 "B.Paste" user)
		(5 "F.SilkS" user "F.Silkscreen")
		(7 "B.SilkS" user "B.Silkscreen")
		(1 "F.Mask" user)
		(3 "B.Mask" user)
		(17 "Dwgs.User" user "User.Drawings")
		(19 "Cmts.User" user "User.Comments")
		(21 "Eco1.User" user "User.Eco1")
		(23 "Eco2.User" user "User.Eco2")
		(25 "Edge.Cuts" user)
		(27 "Margin" user)
		(31 "F.CrtYd" user "F.Courtyard")
		(29 "B.CrtYd" user "B.Courtyard")
		(35 "F.Fab" user)
		(33 "B.Fab" user)
	)
	(footprint "antmicro-footprints:X1QFN-16-1EP_2.5x2.5mm"
		(layer "F.Cu")
		(at 262.5 134.75 90)
		(property "Reference" "U18"
			(at 1.6 -0.6 0)
			(unlocked yes)
			(layer "F.SilkS")
			(effects
				(font
					(size 0.7 0.7)
					(thickness 0.15)
				)
				(justify left bottom)
			)
		)
		(property "Value" "SN74HC595B"
			(at -6.9 2.69 90)
			(unlocked yes)
			(layer "F.Fab")
			(effects
				(font
					(size 0.7 0.7)
					(thickness 0.15)
				)
				(justify left bottom)
			)
		)
		(property "Description" "Shift Register, 74HC595, Serial to Parallel, 1 Element, 8 bit, X1QFN, 16 Pins"
			(at 0 0 90)
			(layer "F.Fab")
			(hide yes)
			(effects
				(font
					(size 1.27 1.27)
					(thickness 0.15)
				)
			)
		)
		(property "Author" "Antmicro"
			(at 397.25 -127.75 0)
			(layer "F.Fab")
			(hide yes)
			(effects
				(font
					(size 1 1)
					(thickness 0.15)
				)
			)
		)
		(property "License" "Apache-2.0"
			(at 397.25 -127.75 0)
			(layer "F.Fab")
			(hide yes)
			(effects
				(font
					(size 1 1)
					(thickness 0.15)
				)
			)
		)
		(property "MPN" "SN74HC595BRWNR"
			(at 397.25 -127.75 0)
			(layer "F.Fab")
			(hide yes)
			(effects
				(font
					(size 1 1)
					(thickness 0.15)
				)
			)
		)
		(property "Manufacturer" "Texas Instruments"
			(at 397.25 -127.75 0)
			(layer "F.Fab")
			(hide yes)
			(effects
				(font
					(size 1 1)
					(thickness 0.15)
				)
			)
		)
		(sheetname "USB PHY")
		(sheetfile "usb-phy.kicad_sch")
		(attr smd)
		(fp_line
			(start 1.35 -1.351)
			(end 1.35 -0.803)
			(stroke
				(width 0.15)
				(type solid)
			)
			(layer "F.SilkS")
		)
		(fp_line
			(start 0.8 -1.351)
			(end 1.35 -1.351)
			(stroke
				(width 0.15)
				(type solid)
			)
			(layer "F.SilkS")
		)
		(fp_line
			(start -1.351 -1.351)
			(end -0.803 -1.351)
			(stroke
				(width 0.15)
				(type solid)
			)
			(layer "F.SilkS")
		)
		(fp_line
			(start 1.35 0.8)
			(end 1.35 1.35)
			(stroke
				(width 0.15)
				(type solid)
			)
			(layer "F.SilkS")
		)
		(fp_line
			(start 1.35 1.35)
			(end 0.8 1.35)
			(stroke
				(width 0.15)
				(type solid)
			)
			(layer "F.SilkS")
		)
		(fp_line
			(start -0.803 1.35)
			(end -1.351 1.35)
			(stroke
				(width 0.15)
				(type solid)
			)
			(layer "F.SilkS")
		)
		(fp_line
			(start -1.351 1.35)
			(end -1.351 0.8)
			(stroke
				(width 0.15)
				(type solid)
			)
			(layer "F.SilkS")
		)
		(fp_circle
			(center -1.752 -0.6)
			(end -1.702 -0.6)
			(stroke
				(width 0.15)
				(type solid)
			)
			(fill yes)
			(layer "F.SilkS")
		)
		(fp_rect
			(start -1.75 -1.75)
			(end 1.749 1.749)
			(stroke
				(width 0.05)
				(type solid)
			)
			(fill no)
			(layer "F.CrtYd")
		)
		(fp_line
			(start -1.25 -1.05)
			(end -1.05 -1.25)
			(stroke
				(width 0.15)
				(type solid)
			)
			(layer "F.Fab")
		)
		(fp_rect
			(start -1.25 -1.25)
			(end 1.249 1.249)
			(stroke
				(width 0.15)
				(type solid)
			)
			(fill no)
			(layer "F.Fab")
		)
		(pad "1" smd roundrect
			(at -1.151 -0.6 90)
			(size 0.6 0.2)
			(layers "F.Cu" "F.Mask" "F.Paste")
			(roundrect_rratio 0.25)
			(net 1160 "unconnected-(U18-QB-Pad1)")
			(pinfunction "QB")
			(pintype "output+no_connect")
		)
		(pad "2" smd roundrect
			(at -1.151 -0.203 90)
			(size 0.6 0.2)
			(layers "F.Cu" "F.Mask" "F.Paste")
			(roundrect_rratio 0.25)
			(net 1161 "unconnected-(U18-QC-Pad2)")
			(pinfunction "QC")
			(pintype "output+no_connect")
		)
		(pad "3" smd roundrect
			(at -1.151 0.2 90)
			(size 0.6 0.2)
			(layers "F.Cu" "F.Mask" "F.Paste")
			(roundrect_rratio 0.25)
			(net 1162 "unconnected-(U18-QD-Pad3)")
			(pinfunction "QD")
			(pintype "output+no_connect")
		)
		(pad "4" smd roundrect
			(at -1.151 0.597 90)
			(size 0.6 0.2)
			(layers "F.Cu" "F.Mask" "F.Paste")
			(roundrect_rratio 0.25)
			(net 912 "/USB PHY/LED_TX0")
			(pinfunction "QE")
			(pintype "output")
		)
		(pad "5" smd roundrect
			(at -0.6 1.148 180)
			(size 0.6 0.2)
			(layers "F.Cu" "F.Mask" "F.Paste")
			(roundrect_rratio 0.25)
			(net 913 "/USB PHY/LED_RX0")
			(pinfunction "QF")
			(pintype "output")
		)
		(pad "6" smd roundrect
			(at -0.203 1.148 180)
			(size 0.6 0.2)
			(layers "F.Cu" "F.Mask" "F.Paste")
			(roundrect_rratio 0.25)
			(net 914 "/USB PHY/LED_TX1")
			(pinfunction "QG")
			(pintype "output")
		)
		(pad "7" smd roundrect
			(at 0.2 1.148 180)
			(size 0.6 0.2)
			(layers "F.Cu" "F.Mask" "F.Paste")
			(roundrect_rratio 0.25)
			(net 915 "/USB PHY/LED_RX1")
			(pinfunction "QH")
			(pintype "output")
		)
		(pad "8" smd roundrect
			(at 0.597 1.148 180)
			(size 0.6 0.2)
			(layers "F.Cu" "F.Mask" "F.Paste")
			(roundrect_rratio 0.25)
			(net 1 "GND")
			(pinfunction "GND")
			(pintype "power_in")
		)
		(pad "9" smd roundrect
			(at 1.148 0.597 90)
			(size 0.6 0.2)
			(layers "F.Cu" "F.Mask" "F.Paste")
			(roundrect_rratio 0.25)
			(net 1163 "unconnected-(U18-QH'-Pad9)")
			(pinfunction "QH'")
			(pintype "output+no_connect")
		)
		(pad "10" smd roundrect
			(at 1.148 0.2 90)
			(size 0.6 0.2)
			(layers "F.Cu" "F.Mask" "F.Paste")
			(roundrect_rratio 0.25)
			(net 707 "/USB PHY/FTDI_3V3")
			(pinfunction "~{SRCLR}")
			(pintype "input")
		)
		(pad "11" smd roundrect
			(at 1.148 -0.203 90)
			(size 0.6 0.2)
			(layers "F.Cu" "F.Mask" "F.Paste")
			(roundrect_rratio 0.25)
			(net 996 "/USB PHY/FTDI_EECLK")
			(pinfunction "SRCLK")
			(pintype "input")
		)
		(pad "12" smd roundrect
			(at 1.148 -0.6 90)
			(size 0.6 0.2)
			(layers "F.Cu" "F.Mask" "F.Paste")
			(roundrect_rratio 0.25)
			(net 997 "/USB PHY/FTDI_EECS")
			(pinfunction "RCLK")
			(pintype "input")
		)
		(pad "13" smd roundrect
			(at 0.597 -1.151 180)
			(size 0.6 0.2)
			(layers "F.Cu" "F.Mask" "F.Paste")
			(roundrect_rratio 0.25)
			(net 918 "/USB PHY/FTDI_PWREN")
			(pinfunction "~{OE}")
			(pintype "input")
		)
		(pad "14" smd roundrect
			(at 0.2 -1.151 180)
			(size 0.6 0.2)
			(layers "F.Cu" "F.Mask" "F.Paste")
			(roundrect_rratio 0.25)
			(net 998 "/USB PHY/FTDI_EEDAT")
			(pinfunction "SER")
			(pintype "input")
		)
		(pad "15" smd roundrect
			(at -0.203 -1.151 180)
			(size 0.6 0.2)
			(layers "F.Cu" "F.Mask" "F.Paste")
			(roundrect_rratio 0.25)
			(net 1164 "unconnected-(U18-QA-Pad15)")
			(pinfunction "QA")
			(pintype "output+no_connect")
		)
		(pad "16" smd roundrect
			(at -0.6 -1.151 180)
			(size 0.6 0.2)
			(layers "F.Cu" "F.Mask" "F.Paste")
			(roundrect_rratio 0.25)
			(net 707 "/USB PHY/FTDI_3V3")
			(pinfunction "VCC")
			(pintype "power_in")
		)
		(pad "17" smd roundrect
			(at 0 0 180)
			(size 1.2 1.2)
			(layers "F.Cu" "F.Mask" "F.Paste")
			(roundrect_rratio 0.04166666667)
			(net 1165 "unconnected-(U18-EP-Pad17)")
			(pinfunction "EP")
			(pintype "no_connect")
		)
	)
	(footprint "antmicro-footprints:R_0402_1005Metric"
		(layer "F.Cu")
		(at 235.9 111.625 180)
		(descr "Resistor SMD 0402")
		(tags "resistor SMD 0402")
		(property "Reference" "R104"
			(at -0.8 -0.375 180)
			(layer "F.SilkS")
			(effects
				(font
					(size 0.7 0.7)
					(thickness 0.15)
				)
				(justify left bottom)
			)
		)
		(property "Value" "R_0R_0402"
			(at 0 1.4 180)
			(layer "F.Fab")
			(effects
				(font
					(size 0.7 0.7)
					(thickness 0.15)
				)
				(justify left bottom)
			)
		)
		(property "Description" "SMD Chip Resistor, Jumper, 0 ohm, 100 mW, 0402 [1005 Metric], Thick Film, General Purpose"
			(at 0 0 180)
			(layer "F.Fab")
			(hide yes)
			(effects
				(font
					(size 1.27 1.27)
					(thickness 0.15)
				)
			)
		)
		(property "Author" "Antmicro"
			(at 471.8 223.25 0)
			(layer "F.Fab")
			(hide yes)
			(effects
				(font
					(size 1 1)
					(thickness 0.15)
				)
			)
		)
		(property "Current" "1A"
			(at 471.8 223.25 0)
			(layer "F.Fab")
			(hide yes)
			(effects
				(font
					(size 1 1)
					(thickness 0.15)
				)
			)
		)
		(property "License" "Apache-2.0"
			(at 471.8 223.25 0)
			(layer "F.Fab")
			(hide yes)
			(effects
				(font
					(size 1 1)
					(thickness 0.15)
				)
			)
		)
		(property "MPN" "ERJ2GE0R00X"
			(at 471.8 223.25 0)
			(layer "F.Fab")
			(hide yes)
			(effects
				(font
					(size 1 1)
					(thickness 0.15)
				)
			)
		)
		(property "Manufacturer" "Panasonic"
			(at 471.8 223.25 0)
			(layer "F.Fab")
			(hide yes)
			(effects
				(font
					(size 1 1)
					(thickness 0.15)
				)
			)
		)
		(property "Tolerance" ""
			(at 471.8 223.25 0)
			(layer "F.Fab")
			(hide yes)
			(effects
				(font
					(size 1 1)
					(thickness 0.15)
				)
			)
		)
		(property "Val" "0R"
			(at 471.8 223.25 0)
			(layer "F.Fab")
			(hide yes)
			(effects
				(font
					(size 1 1)
					(thickness 0.15)
				)
			)
		)
		(sheetname "SPI Flash + SD Card")
		(sheetfile "spi-flash.kicad_sch")
		(attr smd)
		(fp_rect
			(start -0.925 -0.47)
			(end 0.925 0.47)
			(stroke
				(width 0.05)
				(type default)
			)
			(fill no)
			(layer "F.CrtYd")
		)
		(fp_rect
			(start -0.5 -0.25)
			(end 0.5 0.25)
			(stroke
				(width 0.15)
				(type solid)
			)
			(fill no)
			(layer "F.Fab")
		)
		(pad "1" smd roundrect
			(at -0.48 0 180)
			(size 0.59 0.64)
			(layers "F.Cu" "F.Mask" "F.Paste")
			(roundrect_rratio 0.25)
			(net 417 "/FPGA Bank 16 & 17/USR_FLASH_1.DQ3")
			(pintype "passive")
		)
		(pad "2" smd roundrect
			(at 0.48 0 180)
			(size 0.59 0.64)
			(layers "F.Cu" "F.Mask" "F.Paste")
			(roundrect_rratio 0.25)
			(net 911 "/SPI Flash + SD Card/USR_FLASH_1_DQ3")
			(pintype "passive")
		)
	)
	(footprint "antmicro-footprints:C_0402_1005Metric"
		(layer "F.Cu")
		(at 162.2 149.6 90)
		(descr "Capacitor SMD 0402")
		(tags "capacitor SMD 0402")
		(property "Reference" "C177"
			(at -1.5 1.25 90)
			(layer "F.SilkS")
			(effects
				(font
					(size 0.7 0.7)
					(thickness 0.15)
				)
				(justify left bottom)
			)
		)
		(property "Value" "C_100n_0402"
			(at 0 1.169 90)
			(layer "F.Fab")
			(effects
				(font
					(size 0.7 0.7)
					(thickness 0.15)
				)
				(justify left bottom)
			)
		)
		(property "Description" "SMD Multilayer Ceramic Capacitor, 0.1 µF, 50 V, 0402 [1005 Metric], ± 10%, X5R, GRM Series"
			(at 0 0 90)
			(layer "F.Fab")
			(hide yes)
			(effects
				(font
					(size 1.27 1.27)
					(thickness 0.15)
				)
			)
		)
		(property "Author" "Antmicro"
			(at 311.8 -12.6 0)
			(layer "F.Fab")
			(hide yes)
			(effects
				(font
					(size 1 1)
					(thickness 0.15)
				)
			)
		)
		(property "Dielectric" "X5R"
			(at 311.8 -12.6 0)
			(layer "F.Fab")
			(hide yes)
			(effects
				(font
					(size 1 1)
					(thickness 0.15)
				)
			)
		)
		(property "License" "Apache-2.0"
			(at 311.8 -12.6 0)
			(layer "F.Fab")
			(hide yes)
			(effects
				(font
					(size 1 1)
					(thickness 0.15)
				)
			)
		)
		(property "MPN" "GRM155R61H104KE14D"
			(at 311.8 -12.6 0)
			(layer "F.Fab")
			(hide yes)
			(effects
				(font
					(size 1 1)
					(thickness 0.15)
				)
			)
		)
		(property "Manufacturer" "Murata"
			(at 311.8 -12.6 0)
			(layer "F.Fab")
			(hide yes)
			(effects
				(font
					(size 1 1)
					(thickness 0.15)
				)
			)
		)
		(property "Val" "100n"
			(at 311.8 -12.6 0)
			(layer "F.Fab")
			(hide yes)
			(effects
				(font
					(size 1 1)
					(thickness 0.15)
				)
			)
		)
		(property "Voltage" "50V"
			(at 311.8 -12.6 0)
			(layer "F.Fab")
			(hide yes)
			(effects
				(font
					(size 1 1)
					(thickness 0.15)
				)
			)
		)
		(sheetname "DRAM + SRAM")
		(sheetfile "ram.kicad_sch")
		(attr smd)
		(fp_rect
			(start -0.925 -0.47)
			(end 0.925 0.47)
			(stroke
				(width 0.05)
				(type default)
			)
			(fill no)
			(layer "F.CrtYd")
		)
		(fp_line
			(start 0.504 -0.25)
			(end 0.504 0.248)
			(stroke
				(width 0.15)
				(type solid)
			)
			(layer "F.Fab")
		)
		(fp_line
			(start -0.494 -0.25)
			(end 0.504 -0.25)
			(stroke
				(width 0.15)
				(type solid)
			)
			(layer "F.Fab")
		)
		(fp_line
			(start 0.504 0.248)
			(end -0.494 0.248)
			(stroke
				(width 0.15)
				(type solid)
			)
			(layer "F.Fab")
		)
		(fp_line
			(start -0.494 0.248)
			(end -0.494 -0.25)
			(stroke
				(width 0.15)
				(type solid)
			)
			(layer "F.Fab")
		)
		(pad "1" smd roundrect
			(at -0.48 0 90)
			(size 0.59 0.64)
			(layers "F.Cu" "F.Mask" "F.Paste")
			(roundrect_rratio 0.25)
			(net 1 "GND")
			(pintype "passive")
		)
		(pad "2" smd roundrect
			(at 0.48 0 90)
			(size 0.59 0.64)
			(layers "F.Cu" "F.Mask" "F.Paste")
			(roundrect_rratio 0.25)
			(net 25 "+1V35")
			(pintype "passive")
		)
	)
	(footprint "antmicro-footprints:R_0402_1005Metric"
		(layer "F.Cu")
		(at 173.570001 85.210001)
		(descr "Resistor SMD 0402")
		(tags "resistor SMD 0402")
		(property "Reference" "R270"
			(at 0.929999 0.342499 0)
			(layer "F.SilkS")
			(effects
				(font
					(size 0.7 0.7)
					(thickness 0.15)
				)
				(justify left bottom)
			)
		)
		(property "Value" "R_33R_0402"
			(at 0 1.4 0)
			(layer "F.Fab")
			(effects
				(font
					(size 0.7 0.7)
					(thickness 0.15)
				)
				(justify left bottom)
			)
		)
		(property "Description" "SMD Chip Resistor, 33 ohm, ± 1%, 62.5 mW, 0402 [1005 Metric], Thick Film, General Purpose"
			(at 0 0 0)
			(layer "F.Fab")
			(hide yes)
			(effects
				(font
					(size 1.27 1.27)
					(thickness 0.15)
				)
			)
		)
		(property "Author" "Antmicro"
			(at 0 0 0)
			(layer "F.Fab")
			(hide yes)
			(effects
				(font
					(size 1 1)
					(thickness 0.15)
				)
			)
		)
		(property "License" "Apache-2.0"
			(at 0 0 0)
			(layer "F.Fab")
			(hide yes)
			(effects
				(font
					(size 1 1)
					(thickness 0.15)
				)
			)
		)
		(property "MPN" "CR0402-FX-33R0GLF"
			(at 0 0 0)
			(layer "F.Fab")
			(hide yes)
			(effects
				(font
					(size 1 1)
					(thickness 0.15)
				)
			)
		)
		(property "Manufacturer" "Bourns"
			(at 0 0 0)
			(layer "F.Fab")
			(hide yes)
			(effects
				(font
					(size 1 1)
					(thickness 0.15)
				)
			)
		)
		(property "Tolerance" "1%"
			(at 0 0 0)
			(layer "F.Fab")
			(hide yes)
			(effects
				(font
					(size 1 1)
					(thickness 0.15)
				)
			)
		)
		(property "Val" "33R"
			(at 0 0 0)
			(layer "F.Fab")
			(hide yes)
			(effects
				(font
					(size 1 1)
					(thickness 0.15)
				)
			)
		)
		(sheetname "FMC+ HSPC")
		(sheetfile "fmc-hspc.kicad_sch")
		(attr smd)
		(fp_rect
			(start -0.925 -0.47)
			(end 0.925 0.47)
			(stroke
				(width 0.05)
				(type default)
			)
			(fill no)
			(layer "F.CrtYd")
		)
		(fp_rect
			(start -0.5 -0.25)
			(end 0.5 0.25)
			(stroke
				(width 0.15)
				(type solid)
			)
			(fill no)
			(layer "F.Fab")
		)
		(pad "1" smd roundrect
			(at -0.48 0)
			(size 0.59 0.64)
			(layers "F.Cu" "F.Mask" "F.Paste")
			(roundrect_rratio 0.25)
			(net 629 "/FMC+ HSPC/GTR_REFCLK0_R_N")
			(pintype "passive")
		)
		(pad "2" smd roundrect
			(at 0.48 0)
			(size 0.59 0.64)
			(layers "F.Cu" "F.Mask" "F.Paste")
			(roundrect_rratio 0.25)
			(net 630 "/FMC+ HSPC/GTX115.REFCLK0_N")
			(pintype "passive")
		)
	)
	(footprint "antmicro-footprints:C_0402_1005Metric"
		(layer "F.Cu")
		(at 221.5 145.7)
		(descr "Capacitor SMD 0402")
		(tags "capacitor SMD 0402")
		(property "Reference" "C253"
			(at 0.75 0.4 0)
			(layer "F.SilkS")
			(effects
				(font
					(size 0.7 0.7)
					(thickness 0.15)
				)
				(justify left bottom)
			)
		)
		(property "Value" "C_10u_0402"
			(at 0 1.4 0)
			(layer "F.Fab")
			(effects
				(font
					(size 0.7 0.7)
					(thickness 0.15)
				)
				(justify left bottom)
			)
		)
		(property "Description" "SMD Multilayer Ceramic Capacitor, 10 µF, 6.3 V, 0402 [1005 Metric], ± 20%, X5R, CC Series"
			(at 0 0 0)
			(layer "F.Fab")
			(hide yes)
			(effects
				(font
					(size 1.27 1.27)
					(thickness 0.15)
				)
			)
		)
		(property "Author" "Antmicro"
			(at 0 0 0)
			(layer "F.Fab")
			(hide yes)
			(effects
				(font
					(size 1 1)
					(thickness 0.15)
				)
			)
		)
		(property "Dielectric" ""
			(at 0 0 0)
			(layer "F.Fab")
			(hide yes)
			(effects
				(font
					(size 1 1)
					(thickness 0.15)
				)
			)
		)
		(property "License" "Apache-2.0"
			(at 0 0 0)
			(layer "F.Fab")
			(hide yes)
			(effects
				(font
					(size 1 1)
					(thickness 0.15)
				)
			)
		)
		(property "MPN" "CC0402MRX5R5BB106"
			(at 0 0 0)
			(layer "F.Fab")
			(hide yes)
			(effects
				(font
					(size 1 1)
					(thickness 0.15)
				)
			)
		)
		(property "Manufacturer" "YAGEO"
			(at 0 0 0)
			(layer "F.Fab")
			(hide yes)
			(effects
				(font
					(size 1 1)
					(thickness 0.15)
				)
			)
		)
		(property "Val" "10u"
			(at 0 0 0)
			(layer "F.Fab")
			(hide yes)
			(effects
				(font
					(size 1 1)
					(thickness 0.15)
				)
			)
		)
		(property "Voltage" ""
			(at 0 0 0)
			(layer "F.Fab")
			(hide yes)
			(effects
				(font
					(size 1 1)
					(thickness 0.15)
				)
			)
		)
		(sheetname "HDMI + Ethernet")
		(sheetfile "hdmi-ethernet.kicad_sch")
		(attr smd)
		(fp_rect
			(start -0.925 -0.47)
			(end 0.925 0.47)
			(stroke
				(width 0.05)
				(type default)
			)
			(fill no)
			(layer "F.CrtYd")
		)
		(fp_line
			(start -0.494 -0.25)
			(end 0.504 -0.25)
			(stroke
				(width 0.15)
				(type solid)
			)
			(layer "F.Fab")
		)
		(fp_line
			(start -0.494 0.248)
			(end -0.494 -0.25)
			(stroke
				(width 0.15)
				(type solid)
			)
			(layer "F.Fab")
		)
		(fp_line
			(start 0.504 -0.25)
			(end 0.504 0.248)
			(stroke
				(width 0.15)
				(type solid)
			)
			(layer "F.Fab")
		)
		(fp_line
			(start 0.504 0.248)
			(end -0.494 0.248)
			(stroke
				(width 0.15)
				(type solid)
			)
			(layer "F.Fab")
		)
		(pad "1" smd roundrect
			(at -0.48 0)
			(size 0.59 0.64)
			(layers "F.Cu" "F.Mask" "F.Paste")
			(roundrect_rratio 0.25)
			(net 1 "GND")
			(pintype "passive")
		)
		(pad "2" smd roundrect
			(at 0.48 0)
			(size 0.59 0.64)
			(layers "F.Cu" "F.Mask" "F.Paste")
			(roundrect_rratio 0.25)
			(net 26 "+1V8")
			(pintype "passive")
		)
	)
)
